(kicad_pcb
	(version 20241229)
	(generator "pcbnew")
	(generator_version "9.0")
	(general
		(thickness 1.294)
		(legacy_teardrops no)
	)
	(paper "A3")
	(title_block
		(title "Kintex 410T devboard")
		(date "2024-04-03")
		(rev "1.1.2")
		(comment 9 "footprints 957-962 of 975")
	)
	(layers
		(0 "F.Cu" mixed)
		(4 "In1.Cu" power)
		(6 "In2.Cu" power)
		(8 "In3.Cu" mixed)
		(10 "In4.Cu" power)
		(12 "In5.Cu" mixed)
		(14 "In6.Cu" power)
		(16 "In7.Cu" mixed)
		(18 "In8.Cu" power)
		(2 "B.Cu" mixed)
		(9 "F.Adhes" user "F.Adhesive")
		(11 "B.Adhes" user "B.Adhesive")
		(13 "F.Paste" user)
		(15 "B.Paste" user)
		(5 "F.SilkS" user "F.Silkscreen")
		(7 "B.SilkS" user "B.Silkscreen")
		(1 "F.Mask" user)
		(3 "B.Mask" user)
		(17 "Dwgs.User" user "User.Drawings")
		(19 "Cmts.User" user "User.Comments")
		(21 "Eco1.User" user "User.Eco1")
		(23 "Eco2.User" user "User.Eco2")
		(25 "Edge.Cuts" user)
		(27 "Margin" user)
		(31 "F.CrtYd" user "F.Courtyard")
		(29 "B.CrtYd" user "B.Courtyard")
		(35 "F.Fab" user)
		(33 "B.Fab" user)
	)
	(footprint "antmicro-footprints:C_0201"
		(layer "B.Cu")
		(at 201.5 131.25)
		(descr "Capacitor SMD 0201")
		(tags "capacitor SMD 0201")
		(property "Reference" "C127"
			(at 24.375 -28.65 0)
			(layer "B.SilkS")
			(effects
				(font
					(size 0.7 0.7)
					(thickness 0.15)
				)
				(justify right bottom mirror)
			)
		)
		(property "Value" "C_100n_0201"
			(at 0 -1.4 0)
			(layer "B.Fab")
			(effects
				(font
					(size 0.7 0.7)
					(thickness 0.15)
				)
				(justify right bottom mirror)
			)
		)
		(property "Description" "SMD Multilayer Ceramic Capacitor, 0.1 µF, 6.3 V, 0201 [0603 Metric], ± 10%, X6S, CC Series"
			(at 0 0 0)
			(layer "F.Fab")
			(hide yes)
			(effects
				(font
					(size 1.27 1.27)
					(thickness 0.15)
				)
			)
		)
		(property "Author" "Antmicro"
			(at 0 0 0)
			(layer "B.Fab")
			(hide yes)
			(effects
				(font
					(size 1 1)
					(thickness 0.15)
				)
				(justify mirror)
			)
		)
		(property "Dielectric" ""
			(at 0 0 0)
			(layer "B.Fab")
			(hide yes)
			(effects
				(font
					(size 1 1)
					(thickness 0.15)
				)
				(justify mirror)
			)
		)
		(property "License" "Apache-2.0"
			(at 0 0 0)
			(layer "B.Fab")
			(hide yes)
			(effects
				(font
					(size 1 1)
					(thickness 0.15)
				)
				(justify mirror)
			)
		)
		(property "MPN" "CC0201KRX6S5BB104"
			(at 0 0 0)
			(layer "B.Fab")
			(hide yes)
			(effects
				(font
					(size 1 1)
					(thickness 0.15)
				)
				(justify mirror)
			)
		)
		(property "Manufacturer" "YAGEO"
			(at 0 0 0)
			(layer "B.Fab")
			(hide yes)
			(effects
				(font
					(size 1 1)
					(thickness 0.15)
				)
				(justify mirror)
			)
		)
		(property "Val" "100n"
			(at 0 0 0)
			(layer "B.Fab")
			(hide yes)
			(effects
				(font
					(size 1 1)
					(thickness 0.15)
				)
				(justify mirror)
			)
		)
		(property "Voltage" ""
			(at 0 0 0)
			(layer "B.Fab")
			(hide yes)
			(effects
				(font
					(size 1 1)
					(thickness 0.15)
				)
				(justify mirror)
			)
		)
		(sheetname "FPGA supply")
		(sheetfile "fpga-supply.kicad_sch")
		(attr smd)
		(fp_rect
			(start -0.7 0.35)
			(end 0.7 -0.35)
			(stroke
				(width 0.05)
				(type default)
			)
			(fill no)
			(layer "B.CrtYd")
		)
		(fp_rect
			(start 0.3 -0.15)
			(end -0.301 0.149)
			(stroke
				(width 0.15)
				(type solid)
			)
			(fill no)
			(layer "B.Fab")
		)
		(pad "" smd roundrect
			(at -0.349 0.002)
			(size 0.318 0.36)
			(layers "B.Paste")
			(roundrect_rratio 0.25)
		)
		(pad "" smd roundrect
			(at 0.341 0.002)
			(size 0.318 0.36)
			(layers "B.Paste")
			(roundrect_rratio 0.25)
		)
		(pad "1" smd roundrect
			(at -0.321 0.002)
			(size 0.46 0.4)
			(layers "B.Cu" "B.Mask")
			(roundrect_rratio 0.25)
			(net 1 "GND")
			(pintype "passive")
		)
		(pad "2" smd roundrect
			(at 0.32 0.002)
			(size 0.46 0.4)
			(layers "B.Cu" "B.Mask")
			(roundrect_rratio 0.25)
			(net 650 "+1V0")
			(pintype "passive")
		)
	)
	(footprint "antmicro-footprints:R_0402_1005Metric"
		(layer "B.Cu")
		(at 221.715 148.2)
		(descr "Resistor SMD 0402")
		(tags "resistor SMD 0402")
		(property "Reference" "R222"
			(at 0.96 2.334 180)
			(layer "B.SilkS")
			(effects
				(font
					(size 0.7 0.7)
					(thickness 0.15)
				)
				(justify left bottom mirror)
			)
		)
		(property "Value" "R_10k_0402"
			(at 0 -1.4 180)
			(layer "B.Fab")
			(effects
				(font
					(size 0.7 0.7)
					(thickness 0.15)
				)
				(justify left bottom mirror)
			)
		)
		(property "Description" "SMD Chip Resistor, 10 kohm, ± 1%, 62.5 mW, 0402 [1005 Metric], Thick Film, General Purpose"
			(at 0 0 0)
			(layer "F.Fab")
			(hide yes)
			(effects
				(font
					(size 1.27 1.27)
					(thickness 0.15)
				)
			)
		)
		(property "Author" "Antmicro"
			(at 0 0 0)
			(layer "B.Fab")
			(hide yes)
			(effects
				(font
					(size 1 1)
					(thickness 0.15)
				)
				(justify mirror)
			)
		)
		(property "DNP" "DNP"
			(at 0 0 0)
			(layer "B.Fab")
			(hide yes)
			(effects
				(font
					(size 1 1)
					(thickness 0.15)
				)
				(justify mirror)
			)
		)
		(property "License" "Apache-2.0"
			(at 0 0 0)
			(layer "B.Fab")
			(hide yes)
			(effects
				(font
					(size 1 1)
					(thickness 0.15)
				)
				(justify mirror)
			)
		)
		(property "MPN" "CR0402-FX-1002GLF"
			(at 0 0 0)
			(layer "B.Fab")
			(hide yes)
			(effects
				(font
					(size 1 1)
					(thickness 0.15)
				)
				(justify mirror)
			)
		)
		(property "Manufacturer" "Bourns"
			(at 0 0 0)
			(layer "B.Fab")
			(hide yes)
			(effects
				(font
					(size 1 1)
					(thickness 0.15)
				)
				(justify mirror)
			)
		)
		(property "Tolerance" "1%"
			(at 0 0 0)
			(layer "B.Fab")
			(hide yes)
			(effects
				(font
					(size 1 1)
					(thickness 0.15)
				)
				(justify mirror)
			)
		)
		(property "Val" "10k"
			(at 0 0 0)
			(layer "B.Fab")
			(hide yes)
			(effects
				(font
					(size 1 1)
					(thickness 0.15)
				)
				(justify mirror)
			)
		)
		(property "dnp" ""
			(at 0 0 0)
			(layer "B.Fab")
			(hide yes)
			(effects
				(font
					(size 1 1)
					(thickness 0.15)
				)
				(justify mirror)
			)
		)
		(property "exclude_from_bom" ""
			(at 0 0 0)
			(layer "B.Fab")
			(hide yes)
			(effects
				(font
					(size 1 1)
					(thickness 0.15)
				)
				(justify mirror)
			)
		)
		(sheetname "HDMI + Ethernet")
		(sheetfile "hdmi-ethernet.kicad_sch")
		(attr smd exclude_from_bom)
		(fp_rect
			(start -0.925 0.47)
			(end 0.925 -0.47)
			(stroke
				(width 0.05)
				(type default)
			)
			(fill no)
			(layer "B.CrtYd")
		)
		(fp_rect
			(start -0.5 0.25)
			(end 0.5 -0.25)
			(stroke
				(width 0.15)
				(type solid)
			)
			(fill no)
			(layer "B.Fab")
		)
		(pad "1" smd roundrect
			(at -0.48 0)
			(size 0.59 0.64)
			(layers "B.Cu" "B.Mask" "B.Paste")
			(roundrect_rratio 0.25)
			(net 947 "/HDMI + Ethernet/ETH_PHY_RXER")
			(pintype "passive")
		)
		(pad "2" smd roundrect
			(at 0.48 0)
			(size 0.59 0.64)
			(layers "B.Cu" "B.Mask" "B.Paste")
			(roundrect_rratio 0.25)
			(net 26 "+1V8")
			(pintype "passive")
		)
	)
	(footprint "antmicro-footprints:R_0402_1005Metric"
		(layer "B.Cu")
		(at 181.05 168.7125 90)
		(descr "Resistor SMD 0402")
		(tags "resistor SMD 0402")
		(property "Reference" "R307"
			(at 3.6125 0.425 270)
			(layer "B.SilkS")
			(effects
				(font
					(size 0.7 0.7)
					(thickness 0.15)
				)
				(justify left bottom mirror)
			)
		)
		(property "Value" "R_0R_0402"
			(at 0 -1.4 270)
			(layer "B.Fab")
			(effects
				(font
					(size 0.7 0.7)
					(thickness 0.15)
				)
				(justify left bottom mirror)
			)
		)
		(property "Description" "SMD Chip Resistor, Jumper, 0 ohm, 100 mW, 0402 [1005 Metric], Thick Film, General Purpose"
			(at 0 0 90)
			(layer "F.Fab")
			(hide yes)
			(effects
				(font
					(size 1.27 1.27)
					(thickness 0.15)
				)
			)
		)
		(property "Author" "Antmicro"
			(at 349.7625 -12.3375 0)
			(layer "B.Fab")
			(hide yes)
			(effects
				(font
					(size 1 1)
					(thickness 0.15)
				)
				(justify mirror)
			)
		)
		(property "Current" "1A"
			(at 349.7625 -12.3375 0)
			(layer "B.Fab")
			(hide yes)
			(effects
				(font
					(size 1 1)
					(thickness 0.15)
				)
				(justify mirror)
			)
		)
		(property "DNP" "DNP"
			(at 349.7625 -12.3375 0)
			(layer "B.Fab")
			(hide yes)
			(effects
				(font
					(size 1 1)
					(thickness 0.15)
				)
				(justify mirror)
			)
		)
		(property "License" "Apache-2.0"
			(at 349.7625 -12.3375 0)
			(layer "B.Fab")
			(hide yes)
			(effects
				(font
					(size 1 1)
					(thickness 0.15)
				)
				(justify mirror)
			)
		)
		(property "MPN" "ERJ2GE0R00X"
			(at 349.7625 -12.3375 0)
			(layer "B.Fab")
			(hide yes)
			(effects
				(font
					(size 1 1)
					(thickness 0.15)
				)
				(justify mirror)
			)
		)
		(property "Manufacturer" "Panasonic"
			(at 349.7625 -12.3375 0)
			(layer "B.Fab")
			(hide yes)
			(effects
				(font
					(size 1 1)
					(thickness 0.15)
				)
				(justify mirror)
			)
		)
		(property "Tolerance" ""
			(at 349.7625 -12.3375 0)
			(layer "B.Fab")
			(hide yes)
			(effects
				(font
					(size 1 1)
					(thickness 0.15)
				)
				(justify mirror)
			)
		)
		(property "Val" "0R"
			(at 349.7625 -12.3375 0)
			(layer "B.Fab")
			(hide yes)
			(effects
				(font
					(size 1 1)
					(thickness 0.15)
				)
				(justify mirror)
			)
		)
		(property "dnp" ""
			(at 349.7625 -12.3375 0)
			(layer "B.Fab")
			(hide yes)
			(effects
				(font
					(size 1 1)
					(thickness 0.15)
				)
				(justify mirror)
			)
		)
		(property "exclude_from_bom" ""
			(at 349.7625 -12.3375 0)
			(layer "B.Fab")
			(hide yes)
			(effects
				(font
					(size 1 1)
					(thickness 0.15)
				)
				(justify mirror)
			)
		)
		(sheetname "DC-DC Converters")
		(sheetfile "dc-dc.kicad_sch")
		(attr smd exclude_from_bom)
		(fp_rect
			(start -0.925 0.47)
			(end 0.925 -0.47)
			(stroke
				(width 0.05)
				(type default)
			)
			(fill no)
			(layer "B.CrtYd")
		)
		(fp_rect
			(start -0.5 0.25)
			(end 0.5 -0.25)
			(stroke
				(width 0.15)
				(type solid)
			)
			(fill no)
			(layer "B.Fab")
		)
		(pad "1" smd roundrect
			(at -0.48 0 90)
			(size 0.59 0.64)
			(layers "B.Cu" "B.Mask" "B.Paste")
			(roundrect_rratio 0.25)
			(net 957 "/DC-DC Converters/FB6")
			(pintype "passive")
		)
		(pad "2" smd roundrect
			(at 0.48 0 90)
			(size 0.59 0.64)
			(layers "B.Cu" "B.Mask" "B.Paste")
			(roundrect_rratio 0.25)
			(net 1220 "/DC-DC Converters/SENSE_3V3_2_P")
			(pintype "passive")
		)
	)
	(footprint "antmicro-footprints:C_0402_1005Metric"
		(layer "B.Cu")
		(at 206 118.5 180)
		(descr "Capacitor SMD 0402")
		(tags "capacitor SMD 0402")
		(property "Reference" "C75"
			(at -1.15 0.475 0)
			(layer "B.SilkS")
			(effects
				(font
					(size 0.7 0.7)
					(thickness 0.15)
				)
				(justify left bottom mirror)
			)
		)
		(property "Value" "C_100n_0402"
			(at 0 -1.169 0)
			(layer "B.Fab")
			(effects
				(font
					(size 0.7 0.7)
					(thickness 0.15)
				)
				(justify left bottom mirror)
			)
		)
		(property "Description" "SMD Multilayer Ceramic Capacitor, 0.1 µF, 50 V, 0402 [1005 Metric], ± 10%, X5R, GRM Series"
			(at 0 0 180)
			(layer "F.Fab")
			(hide yes)
			(effects
				(font
					(size 1.27 1.27)
					(thickness 0.15)
				)
			)
		)
		(property "Author" "Antmicro"
			(at 412 237 0)
			(layer "B.Fab")
			(hide yes)
			(effects
				(font
					(size 1 1)
					(thickness 0.15)
				)
				(justify mirror)
			)
		)
		(property "Dielectric" "X5R"
			(at 412 237 0)
			(layer "B.Fab")
			(hide yes)
			(effects
				(font
					(size 1 1)
					(thickness 0.15)
				)
				(justify mirror)
			)
		)
		(property "License" "Apache-2.0"
			(at 412 237 0)
			(layer "B.Fab")
			(hide yes)
			(effects
				(font
					(size 1 1)
					(thickness 0.15)
				)
				(justify mirror)
			)
		)
		(property "MPN" "GRM155R61H104KE14D"
			(at 412 237 0)
			(layer "B.Fab")
			(hide yes)
			(effects
				(font
					(size 1 1)
					(thickness 0.15)
				)
				(justify mirror)
			)
		)
		(property "Manufacturer" "Murata"
			(at 412 237 0)
			(layer "B.Fab")
			(hide yes)
			(effects
				(font
					(size 1 1)
					(thickness 0.15)
				)
				(justify mirror)
			)
		)
		(property "Val" "100n"
			(at 412 237 0)
			(layer "B.Fab")
			(hide yes)
			(effects
				(font
					(size 1 1)
					(thickness 0.15)
				)
				(justify mirror)
			)
		)
		(property "Voltage" "50V"
			(at 412 237 0)
			(layer "B.Fab")
			(hide yes)
			(effects
				(font
					(size 1 1)
					(thickness 0.15)
				)
				(justify mirror)
			)
		)
		(sheetname "FPGA Bank 16 & 17")
		(sheetfile "fpga-bank-16-17.kicad_sch")
		(attr smd)
		(fp_rect
			(start -0.925 0.47)
			(end 0.925 -0.47)
			(stroke
				(width 0.05)
				(type default)
			)
			(fill no)
			(layer "B.CrtYd")
		)
		(fp_line
			(start 0.504 0.25)
			(end 0.504 -0.248)
			(stroke
				(width 0.15)
				(type solid)
			)
			(layer "B.Fab")
		)
		(fp_line
			(start 0.504 -0.248)
			(end -0.494 -0.248)
			(stroke
				(width 0.15)
				(type solid)
			)
			(layer "B.Fab")
		)
		(fp_line
			(start -0.494 0.25)
			(end 0.504 0.25)
			(stroke
				(width 0.15)
				(type solid)
			)
			(layer "B.Fab")
		)
		(fp_line
			(start -0.494 -0.248)
			(end -0.494 0.25)
			(stroke
				(width 0.15)
				(type solid)
			)
			(layer "B.Fab")
		)
		(pad "1" smd roundrect
			(at -0.48 0 180)
			(size 0.59 0.64)
			(layers "B.Cu" "B.Mask" "B.Paste")
			(roundrect_rratio 0.25)
			(net 1 "GND")
			(pintype "passive")
		)
		(pad "2" smd roundrect
			(at 0.48 0 180)
			(size 0.59 0.64)
			(layers "B.Cu" "B.Mask" "B.Paste")
			(roundrect_rratio 0.25)
			(net 24 "+3V3")
			(pintype "passive")
		)
	)
	(footprint "antmicro-footprints:C_0402_1005Metric"
		(layer "B.Cu")
		(at 214.64 115.92 90)
		(descr "Capacitor SMD 0402")
		(tags "capacitor SMD 0402")
		(property "Reference" "C21"
			(at 1.025 1.225 270)
			(layer "B.SilkS")
			(effects
				(font
					(size 0.7 0.7)
					(thickness 0.15)
				)
				(justify left bottom mirror)
			)
		)
		(property "Value" "C_100n_0402"
			(at 0 -1.169 270)
			(layer "B.Fab")
			(effects
				(font
					(size 0.7 0.7)
					(thickness 0.15)
				)
				(justify left bottom mirror)
			)
		)
		(property "Description" "SMD Multilayer Ceramic Capacitor, 0.1 µF, 50 V, 0402 [1005 Metric], ± 10%, X5R, GRM Series"
			(at 0 0 90)
			(layer "F.Fab")
			(hide yes)
			(effects
				(font
					(size 1.27 1.27)
					(thickness 0.15)
				)
			)
		)
		(property "Author" "Antmicro"
			(at 330.56 -98.72 0)
			(layer "B.Fab")
			(hide yes)
			(effects
				(font
					(size 1 1)
					(thickness 0.15)
				)
				(justify mirror)
			)
		)
		(property "Dielectric" "X5R"
			(at 330.56 -98.72 0)
			(layer "B.Fab")
			(hide yes)
			(effects
				(font
					(size 1 1)
					(thickness 0.15)
				)
				(justify mirror)
			)
		)
		(property "License" "Apache-2.0"
			(at 330.56 -98.72 0)
			(layer "B.Fab")
			(hide yes)
			(effects
				(font
					(size 1 1)
					(thickness 0.15)
				)
				(justify mirror)
			)
		)
		(property "MPN" "GRM155R61H104KE14D"
			(at 330.56 -98.72 0)
			(layer "B.Fab")
			(hide yes)
			(effects
				(font
					(size 1 1)
					(thickness 0.15)
				)
				(justify mirror)
			)
		)
		(property "Manufacturer" "Murata"
			(at 330.56 -98.72 0)
			(layer "B.Fab")
			(hide yes)
			(effects
				(font
					(size 1 1)
					(thickness 0.15)
				)
				(justify mirror)
			)
		)
		(property "Val" "100n"
			(at 330.56 -98.72 0)
			(layer "B.Fab")
			(hide yes)
			(effects
				(font
					(size 1 1)
					(thickness 0.15)
				)
				(justify mirror)
			)
		)
		(property "Voltage" "50V"
			(at 330.56 -98.72 0)
			(layer "B.Fab")
			(hide yes)
			(effects
				(font
					(size 1 1)
					(thickness 0.15)
				)
				(justify mirror)
			)
		)
		(sheetname "FPGA Bank 16 & 17")
		(sheetfile "fpga-bank-16-17.kicad_sch")
		(attr smd)
		(fp_rect
			(start -0.925 0.47)
			(end 0.925 -0.47)
			(stroke
				(width 0.05)
				(type default)
			)
			(fill no)
			(layer "B.CrtYd")
		)
		(fp_line
			(start 0.504 -0.248)
			(end -0.494 -0.248)
			(stroke
				(width 0.15)
				(type solid)
			)
			(layer "B.Fab")
		)
		(fp_line
			(start -0.494 -0.248)
			(end -0.494 0.25)
			(stroke
				(width 0.15)
				(type solid)
			)
			(layer "B.Fab")
		)
		(fp_line
			(start 0.504 0.25)
			(end 0.504 -0.248)
			(stroke
				(width 0.15)
				(type solid)
			)
			(layer "B.Fab")
		)
		(fp_line
			(start -0.494 0.25)
			(end 0.504 0.25)
			(stroke
				(width 0.15)
				(type solid)
			)
			(layer "B.Fab")
		)
		(pad "1" smd roundrect
			(at -0.48 0 90)
			(size 0.59 0.64)
			(layers "B.Cu" "B.Mask" "B.Paste")
			(roundrect_rratio 0.25)
			(net 1 "GND")
			(pintype "passive")
		)
		(pad "2" smd roundrect
			(at 0.48 0 90)
			(size 0.59 0.64)
			(layers "B.Cu" "B.Mask" "B.Paste")
			(roundrect_rratio 0.25)
			(net 3 "VCC_USR_B")
			(pintype "passive")
		)
	)
	(footprint "antmicro-footprints:R_0402_1005Metric"
		(layer "B.Cu")
		(at 200.891252 96.95 90)
		(descr "Resistor SMD 0402")
		(tags "resistor SMD 0402")
		(property "Reference" "R218"
			(at -3.35 0.333748 270)
			(layer "B.SilkS")
			(effects
				(font
					(size 0.7 0.7)
					(thickness 0.15)
				)
				(justify left bottom mirror)
			)
		)
		(property "Value" "R_2k2_0402"
			(at 0 -1.4 270)
			(layer "B.Fab")
			(effects
				(font
					(size 0.7 0.7)
					(thickness 0.15)
				)
				(justify left bottom mirror)
			)
		)
		(property "Description" "SMD Chip Resistor, 2.2 kohm, ± 1%, 62.5 mW, 0402 [1005 Metric], Thick Film, General Purpose"
			(at 0 0 90)
			(layer "F.Fab")
			(hide yes)
			(effects
				(font
					(size 1.27 1.27)
					(thickness 0.15)
				)
			)
		)
		(property "Author" "Antmicro"
			(at 297.841252 -103.941252 0)
			(layer "B.Fab")
			(hide yes)
			(effects
				(font
					(size 1 1)
					(thickness 0.15)
				)
				(justify mirror)
			)
		)
		(property "DNP" "DNP"
			(at 297.841252 -103.941252 0)
			(layer "B.Fab")
			(hide yes)
			(effects
				(font
					(size 1 1)
					(thickness 0.15)
				)
				(justify mirror)
			)
		)
		(property "License" "Apache-2.0"
			(at 297.841252 -103.941252 0)
			(layer "B.Fab")
			(hide yes)
			(effects
				(font
					(size 1 1)
					(thickness 0.15)
				)
				(justify mirror)
			)
		)
		(property "MPN" "CR0402-FX-2201GLF"
			(at 297.841252 -103.941252 0)
			(layer "B.Fab")
			(hide yes)
			(effects
				(font
					(size 1 1)
					(thickness 0.15)
				)
				(justify mirror)
			)
		)
		(property "Manufacturer" "Bourns"
			(at 297.841252 -103.941252 0)
			(layer "B.Fab")
			(hide yes)
			(effects
				(font
					(size 1 1)
					(thickness 0.15)
				)
				(justify mirror)
			)
		)
		(property "Tolerance" "1%"
			(at 297.841252 -103.941252 0)
			(layer "B.Fab")
			(hide yes)
			(effects
				(font
					(size 1 1)
					(thickness 0.15)
				)
				(justify mirror)
			)
		)
		(property "Val" "2k2"
			(at 297.841252 -103.941252 0)
			(layer "B.Fab")
			(hide yes)
			(effects
				(font
					(size 1 1)
					(thickness 0.15)
				)
				(justify mirror)
			)
		)
		(property "dnp" ""
			(at 297.841252 -103.941252 0)
			(layer "B.Fab")
			(hide yes)
			(effects
				(font
					(size 1 1)
					(thickness 0.15)
				)
				(justify mirror)
			)
		)
		(property "exclude_from_bom" ""
			(at 297.841252 -103.941252 0)
			(layer "B.Fab")
			(hide yes)
			(effects
				(font
					(size 1 1)
					(thickness 0.15)
				)
				(justify mirror)
			)
		)
		(sheetname "HDMI + Ethernet")
		(sheetfile "hdmi-ethernet.kicad_sch")
		(attr smd exclude_from_bom)
		(fp_rect
			(start -0.925 0.47)
			(end 0.925 -0.47)
			(stroke
				(width 0.05)
				(type default)
			)
			(fill no)
			(layer "B.CrtYd")
		)
		(fp_rect
			(start -0.5 0.25)
			(end 0.5 -0.25)
			(stroke
				(width 0.15)
				(type solid)
			)
			(fill no)
			(layer "B.Fab")
		)
		(pad "1" smd roundrect
			(at -0.48 0 90)
			(size 0.59 0.64)
			(layers "B.Cu" "B.Mask" "B.Paste")
			(roundrect_rratio 0.25)
			(net 510 "/FPGA Bank 16 & 17/GBE_RGMII.REFCLK")
			(pintype "passive")
		)
		(pad "2" smd roundrect
			(at 0.48 0 90)
			(size 0.59 0.64)
			(layers "B.Cu" "B.Mask" "B.Paste")
			(roundrect_rratio 0.25)
			(net 1 "GND")
			(pintype "passive")
		)
	)
)
